(kicad_pcb
	(version 20260206)
	(generator "pcbnew")
	(generator_version "10.0")
	(general
		(thickness 1.6)
		(legacy_teardrops no)
	)
	(paper "A4")
	(title_block
		(title "04192023_DAF0TMB3IC0_F0TG_MB_C_brd_V02_OCP.brd")
		(comment 1 "Grand Teton / footprints 1724-1729 of 8354")
	)
	(layers
		(0 "F.Cu" signal "TOP")
		(4 "In1.Cu" signal "GND")
		(6 "In2.Cu" signal "IN1")
		(8 "In3.Cu" signal "GND1")
		(10 "In4.Cu" signal "IN2")
		(12 "In5.Cu" signal "GND2")
		(14 "In6.Cu" signal "IN3")
		(16 "In7.Cu" signal "GND3")
		(18 "In8.Cu" signal "VCC")
		(20 "In9.Cu" signal "VCC1")
		(22 "In10.Cu" signal "GND4")
		(24 "In11.Cu" signal "IN4")
		(26 "In12.Cu" signal "GND5")
		(28 "In13.Cu" signal "IN5")
		(30 "In14.Cu" signal "GND6")
		(32 "In15.Cu" signal "IN6")
		(34 "In16.Cu" signal "GND7")
		(2 "B.Cu" signal "BOTTOM")
		(9 "F.Adhes" user "F.Adhesive")
		(11 "B.Adhes" user "B.Adhesive")
		(13 "F.Paste" user "Package Geometry/Pastemask Top")
		(15 "B.Paste" user "Package Geometry/Pastemask Bottom")
		(5 "F.SilkS" user "Ref Des/Silkscreen Top")
		(7 "B.SilkS" user "Ref Des/Silkscreen Bottom")
		(1 "F.Mask" user "Board Geometry/Soldermask Top")
		(3 "B.Mask" user "Board Geometry/Soldermask Bottom")
		(17 "Dwgs.User" user "User.Drawings")
		(19 "Cmts.User" user "User.Comments")
		(21 "Eco1.User" user "User.Eco1")
		(23 "Eco2.User" user "User.Eco2")
		(25 "Edge.Cuts" user "Board Geometry/Outline")
		(27 "Margin" user)
		(31 "F.CrtYd" user "Package Geometry/Place Bound Top")
		(29 "B.CrtYd" user "Package Geometry/Place Bound Bottom")
		(35 "F.Fab" user "Ref Des/Assembly Top")
		(33 "B.Fab" user "Ref Des/Assembly Bottom")
	)
	(footprint ""
		(layer "F.Cu")
		(at 384.465576 -62.97295 90)
		(property "Reference" "C87"
			(at 0 0 90)
			(layer "F.SilkS")
			(hide yes)
			(effects
				(font
					(size 1.27 1.27)
				)
			)
		)
		(property "Value" ""
			(at 0 0 90)
			(layer "F.Fab")
			(effects
				(font
					(size 1.27 1.27)
				)
			)
		)
		(duplicate_pad_numbers_are_jumpers no)
		(fp_line
			(start 0.7874 -0.4064)
			(end 0.7874 0.4064)
			(stroke
				(width 0.1524)
				(type default)
			)
			(layer "F.SilkS")
		)
		(fp_line
			(start -0.7874 -0.4064)
			(end 0.7874 -0.4064)
			(stroke
				(width 0.1524)
				(type default)
			)
			(layer "F.SilkS")
		)
		(fp_line
			(start 0.7874 0.4064)
			(end -0.7874 0.4064)
			(stroke
				(width 0.1524)
				(type default)
			)
			(layer "F.SilkS")
		)
		(fp_line
			(start -0.7874 0.4064)
			(end -0.7874 -0.4064)
			(stroke
				(width 0.1524)
				(type default)
			)
			(layer "F.SilkS")
		)
		(fp_line
			(start -0.12065 -0.305054)
			(end -0.12065 -0.2794)
			(stroke
				(width 0.1)
				(type default)
			)
			(layer "F.Fab")
		)
		(fp_line
			(start -0.67945 -0.305054)
			(end -0.12065 -0.305054)
			(stroke
				(width 0.1)
				(type default)
			)
			(layer "F.Fab")
		)
		(fp_line
			(start 0.67945 -0.3048)
			(end 0.67945 0.3048)
			(stroke
				(width 0.1)
				(type default)
			)
			(layer "F.Fab")
		)
		(fp_line
			(start 0.12065 -0.3048)
			(end 0.67945 -0.3048)
			(stroke
				(width 0.1)
				(type default)
			)
			(layer "F.Fab")
		)
		(fp_line
			(start 0.12065 -0.2794)
			(end 0.12065 -0.3048)
			(stroke
				(width 0.1)
				(type default)
			)
			(layer "F.Fab")
		)
		(fp_line
			(start -0.12065 -0.2794)
			(end 0.12065 -0.2794)
			(stroke
				(width 0.1)
				(type default)
			)
			(layer "F.Fab")
		)
		(fp_line
			(start 0.120396 0.2794)
			(end -0.12065 0.2794)
			(stroke
				(width 0.1)
				(type default)
			)
			(layer "F.Fab")
		)
		(fp_line
			(start -0.12065 0.2794)
			(end -0.12065 0.3048)
			(stroke
				(width 0.1)
				(type default)
			)
			(layer "F.Fab")
		)
		(fp_line
			(start 0.67945 0.3048)
			(end 0.120396 0.3048)
			(stroke
				(width 0.1)
				(type default)
			)
			(layer "F.Fab")
		)
		(fp_line
			(start 0.120396 0.3048)
			(end 0.120396 0.2794)
			(stroke
				(width 0.1)
				(type default)
			)
			(layer "F.Fab")
		)
		(fp_line
			(start -0.12065 0.3048)
			(end -0.67945 0.3048)
			(stroke
				(width 0.1)
				(type default)
			)
			(layer "F.Fab")
		)
		(fp_line
			(start -0.67945 0.3048)
			(end -0.67945 -0.305054)
			(stroke
				(width 0.1)
				(type default)
			)
			(layer "F.Fab")
		)
		(pad "1" smd circle
			(at -0.40005 0 90)
			(size 0 0)
			(layers "F.Cu" "F.Mask" "F.Paste")
			(net "HDT_HDR_DBREQ_N")
		)
		(pad "2" smd circle
			(at 0.40005 0 90)
			(size 0 0)
			(layers "F.Cu" "F.Mask" "F.Paste")
			(net "GND")
		)
	)
	(footprint ""
		(layer "F.Cu")
		(at 362.267246 -261.747762 -90)
		(property "Reference" "C2622"
			(at 0 0 270)
			(layer "F.SilkS")
			(hide yes)
			(effects
				(font
					(size 1.27 1.27)
				)
			)
		)
		(property "Value" ""
			(at 0 0 270)
			(layer "F.Fab")
			(effects
				(font
					(size 1.27 1.27)
				)
			)
		)
		(duplicate_pad_numbers_are_jumpers no)
		(fp_line
			(start -0.7874 0.4064)
			(end -0.7874 -0.4064)
			(stroke
				(width 0.1524)
				(type default)
			)
			(layer "F.SilkS")
		)
		(fp_line
			(start 0.7874 0.4064)
			(end -0.7874 0.4064)
			(stroke
				(width 0.1524)
				(type default)
			)
			(layer "F.SilkS")
		)
		(fp_line
			(start -0.7874 -0.4064)
			(end 0.7874 -0.4064)
			(stroke
				(width 0.1524)
				(type default)
			)
			(layer "F.SilkS")
		)
		(fp_line
			(start 0.7874 -0.4064)
			(end 0.7874 0.4064)
			(stroke
				(width 0.1524)
				(type default)
			)
			(layer "F.SilkS")
		)
		(fp_line
			(start -0.67945 0.3048)
			(end -0.67945 -0.305054)
			(stroke
				(width 0.1)
				(type default)
			)
			(layer "F.Fab")
		)
		(fp_line
			(start -0.12065 0.3048)
			(end -0.67945 0.3048)
			(stroke
				(width 0.1)
				(type default)
			)
			(layer "F.Fab")
		)
		(fp_line
			(start 0.120396 0.3048)
			(end 0.120396 0.2794)
			(stroke
				(width 0.1)
				(type default)
			)
			(layer "F.Fab")
		)
		(fp_line
			(start 0.67945 0.3048)
			(end 0.120396 0.3048)
			(stroke
				(width 0.1)
				(type default)
			)
			(layer "F.Fab")
		)
		(fp_line
			(start -0.12065 0.2794)
			(end -0.12065 0.3048)
			(stroke
				(width 0.1)
				(type default)
			)
			(layer "F.Fab")
		)
		(fp_line
			(start 0.120396 0.2794)
			(end -0.12065 0.2794)
			(stroke
				(width 0.1)
				(type default)
			)
			(layer "F.Fab")
		)
		(fp_line
			(start -0.12065 -0.2794)
			(end 0.12065 -0.2794)
			(stroke
				(width 0.1)
				(type default)
			)
			(layer "F.Fab")
		)
		(fp_line
			(start 0.12065 -0.2794)
			(end 0.12065 -0.3048)
			(stroke
				(width 0.1)
				(type default)
			)
			(layer "F.Fab")
		)
		(fp_line
			(start 0.12065 -0.3048)
			(end 0.67945 -0.3048)
			(stroke
				(width 0.1)
				(type default)
			)
			(layer "F.Fab")
		)
		(fp_line
			(start 0.67945 -0.3048)
			(end 0.67945 0.3048)
			(stroke
				(width 0.1)
				(type default)
			)
			(layer "F.Fab")
		)
		(fp_line
			(start -0.67945 -0.305054)
			(end -0.12065 -0.305054)
			(stroke
				(width 0.1)
				(type default)
			)
			(layer "F.Fab")
		)
		(fp_line
			(start -0.12065 -0.305054)
			(end -0.12065 -0.2794)
			(stroke
				(width 0.1)
				(type default)
			)
			(layer "F.Fab")
		)
		(pad "1" smd circle
			(at -0.40005 0 270)
			(size 0 0)
			(layers "F.Cu" "F.Mask" "F.Paste")
			(net "PVDD11_S3_P0")
		)
		(pad "2" smd circle
			(at 0.40005 0 270)
			(size 0 0)
			(layers "F.Cu" "F.Mask" "F.Paste")
			(net "GND")
		)
	)
	(footprint ""
		(layer "F.Cu")
		(at 279.513792 -117.69217 180)
		(property "Reference" "R3393"
			(at 0 0 180)
			(layer "F.SilkS")
			(hide yes)
			(effects
				(font
					(size 1.27 1.27)
				)
			)
		)
		(property "Value" ""
			(at 0 0 180)
			(layer "F.Fab")
			(effects
				(font
					(size 1.27 1.27)
				)
			)
		)
		(duplicate_pad_numbers_are_jumpers no)
		(fp_line
			(start 0.7874 0.4064)
			(end -0.7874 0.4064)
			(stroke
				(width 0.1524)
				(type default)
			)
			(layer "F.SilkS")
		)
		(fp_line
			(start 0.7874 -0.4064)
			(end 0.7874 0.4064)
			(stroke
				(width 0.1524)
				(type default)
			)
			(layer "F.SilkS")
		)
		(fp_line
			(start -0.7874 0.4064)
			(end -0.7874 -0.4064)
			(stroke
				(width 0.1524)
				(type default)
			)
			(layer "F.SilkS")
		)
		(fp_line
			(start -0.7874 -0.4064)
			(end 0.7874 -0.4064)
			(stroke
				(width 0.1524)
				(type default)
			)
			(layer "F.SilkS")
		)
		(fp_line
			(start 0.67945 0.3048)
			(end 0.120396 0.3048)
			(stroke
				(width 0.1)
				(type default)
			)
			(layer "F.Fab")
		)
		(fp_line
			(start 0.67945 -0.3048)
			(end 0.67945 0.3048)
			(stroke
				(width 0.1)
				(type default)
			)
			(layer "F.Fab")
		)
		(fp_line
			(start 0.12065 -0.2794)
			(end 0.12065 -0.3048)
			(stroke
				(width 0.1)
				(type default)
			)
			(layer "F.Fab")
		)
		(fp_line
			(start 0.12065 -0.3048)
			(end 0.67945 -0.3048)
			(stroke
				(width 0.1)
				(type default)
			)
			(layer "F.Fab")
		)
		(fp_line
			(start 0.120396 0.3048)
			(end 0.120396 0.2794)
			(stroke
				(width 0.1)
				(type default)
			)
			(layer "F.Fab")
		)
		(fp_line
			(start 0.120396 0.2794)
			(end -0.12065 0.2794)
			(stroke
				(width 0.1)
				(type default)
			)
			(layer "F.Fab")
		)
		(fp_line
			(start -0.12065 0.3048)
			(end -0.67945 0.3048)
			(stroke
				(width 0.1)
				(type default)
			)
			(layer "F.Fab")
		)
		(fp_line
			(start -0.12065 0.2794)
			(end -0.12065 0.3048)
			(stroke
				(width 0.1)
				(type default)
			)
			(layer "F.Fab")
		)
		(fp_line
			(start -0.12065 -0.2794)
			(end 0.12065 -0.2794)
			(stroke
				(width 0.1)
				(type default)
			)
			(layer "F.Fab")
		)
		(fp_line
			(start -0.12065 -0.305054)
			(end -0.12065 -0.2794)
			(stroke
				(width 0.1)
				(type default)
			)
			(layer "F.Fab")
		)
		(fp_line
			(start -0.67945 0.3048)
			(end -0.67945 -0.305054)
			(stroke
				(width 0.1)
				(type default)
			)
			(layer "F.Fab")
		)
		(fp_line
			(start -0.67945 -0.305054)
			(end -0.12065 -0.305054)
			(stroke
				(width 0.1)
				(type default)
			)
			(layer "F.Fab")
		)
		(pad "1" smd circle
			(at -0.40005 0 180)
			(size 0 0)
			(layers "F.Cu" "F.Mask" "F.Paste")
			(net "SMB_IOEXP_3V3AUX_SCL_R")
		)
		(pad "2" smd circle
			(at 0.40005 0 180)
			(size 0 0)
			(layers "F.Cu" "F.Mask" "F.Paste")
			(net "SMB_IOEXP_3V3AUX_SCL")
		)
	)
	(footprint ""
		(layer "F.Cu")
		(at 364.196122 -187.088526 180)
		(property "Reference" "PL51"
			(at 3.7465 7.340854 0)
			(unlocked yes)
			(layer "F.SilkS")
			(effects
				(font
					(size 0.7874 0.5842)
					(thickness 0.1524)
				)
				(justify left)
			)
		)
		(property "Value" ""
			(at 0 0 180)
			(layer "F.Fab")
			(effects
				(font
					(size 1.27 1.27)
				)
			)
		)
		(duplicate_pad_numbers_are_jumpers no)
		(fp_line
			(start 3.750056 5.500116)
			(end 3.750056 -5.500116)
			(stroke
				(width 0.1524)
				(type default)
			)
			(layer "F.SilkS")
		)
		(fp_line
			(start 3.750056 -5.500116)
			(end 2.393442 -5.500116)
			(stroke
				(width 0.1524)
				(type default)
			)
			(layer "F.SilkS")
		)
		(fp_line
			(start 2.393442 5.500116)
			(end 3.750056 5.500116)
			(stroke
				(width 0.1524)
				(type default)
			)
			(layer "F.SilkS")
		)
		(fp_line
			(start -2.393442 5.500116)
			(end -3.750056 5.500116)
			(stroke
				(width 0.1524)
				(type default)
			)
			(layer "F.SilkS")
		)
		(fp_line
			(start -3.750056 5.500116)
			(end -3.750056 -5.500116)
			(stroke
				(width 0.1524)
				(type default)
			)
			(layer "F.SilkS")
		)
		(fp_line
			(start -3.750056 -5.500116)
			(end -2.393442 -5.500116)
			(stroke
				(width 0.1524)
				(type default)
			)
			(layer "F.SilkS")
		)
		(fp_poly
			(pts
				(xy -4.035806 -3.262122) (xy -4.395216 -2.1844) (xy -5.113528 -2.902712)
			)
			(stroke
				(width 0)
				(type default)
			)
			(fill yes)
			(layer "F.SilkS")
		)
		(fp_line
			(start 3.750056 5.500116)
			(end 3.750056 -5.500116)
			(stroke
				(width 0.1)
				(type default)
			)
			(layer "F.Fab")
		)
		(fp_line
			(start 3.750056 -5.500116)
			(end -3.750056 -5.500116)
			(stroke
				(width 0.1)
				(type default)
			)
			(layer "F.Fab")
		)
		(fp_line
			(start -3.750056 5.500116)
			(end 3.750056 5.500116)
			(stroke
				(width 0.1)
				(type default)
			)
			(layer "F.Fab")
		)
		(fp_line
			(start -3.750056 -5.500116)
			(end -3.750056 5.500116)
			(stroke
				(width 0.1)
				(type default)
			)
			(layer "F.Fab")
		)
		(fp_poly
			(pts
				(xy -4.9276 -4.757928) (xy -4.9276 -3.741928) (xy -3.9116 -4.249928)
			)
			(stroke
				(width 0)
				(type default)
			)
			(fill yes)
			(layer "F.Fab")
		)
		(pad "1" smd rect
			(at 0 -4.249928 90)
			(size 2.413 4.5212)
			(layers "F.Cu" "F.Mask" "F.Paste")
			(net "SW_PVDDCR_CPU0_P0_SW1")
		)
		(pad "2" smd rect
			(at 0 -1.175004 90)
			(size 1.3716 4.5212)
			(layers "F.Cu" "F.Mask" "F.Paste")
			(net "IND_CPU0_P0_CPL5")
		)
		(pad "3" smd rect
			(at 0 1.175004 90)
			(size 1.3716 4.5212)
			(layers "F.Cu" "F.Mask" "F.Paste")
			(net "IND_CPU0_P0_CPL1")
		)
		(pad "4" smd rect
			(at 0 4.249928 90)
			(size 2.413 4.5212)
			(layers "F.Cu" "F.Mask" "F.Paste")
			(net "PVDDCR_CPU0_P0")
		)
	)
	(footprint ""
		(layer "F.Cu")
		(at 113.105946 -258.795266)
		(property "Reference" "C2442"
			(at 0 0 0)
			(layer "F.SilkS")
			(hide yes)
			(effects
				(font
					(size 1.27 1.27)
				)
			)
		)
		(property "Value" ""
			(at 0 0 0)
			(layer "F.Fab")
			(effects
				(font
					(size 1.27 1.27)
				)
			)
		)
		(duplicate_pad_numbers_are_jumpers no)
		(fp_line
			(start -0.7874 -0.4064)
			(end 0.7874 -0.4064)
			(stroke
				(width 0.1524)
				(type default)
			)
			(layer "F.SilkS")
		)
		(fp_line
			(start -0.7874 0.4064)
			(end -0.7874 -0.4064)
			(stroke
				(width 0.1524)
				(type default)
			)
			(layer "F.SilkS")
		)
		(fp_line
			(start 0.7874 -0.4064)
			(end 0.7874 0.4064)
			(stroke
				(width 0.1524)
				(type default)
			)
			(layer "F.SilkS")
		)
		(fp_line
			(start 0.7874 0.4064)
			(end -0.7874 0.4064)
			(stroke
				(width 0.1524)
				(type default)
			)
			(layer "F.SilkS")
		)
		(fp_line
			(start -0.67945 -0.305054)
			(end -0.12065 -0.305054)
			(stroke
				(width 0.1)
				(type default)
			)
			(layer "F.Fab")
		)
		(fp_line
			(start -0.67945 0.3048)
			(end -0.67945 -0.305054)
			(stroke
				(width 0.1)
				(type default)
			)
			(layer "F.Fab")
		)
		(fp_line
			(start -0.12065 -0.305054)
			(end -0.12065 -0.2794)
			(stroke
				(width 0.1)
				(type default)
			)
			(layer "F.Fab")
		)
		(fp_line
			(start -0.12065 -0.2794)
			(end 0.12065 -0.2794)
			(stroke
				(width 0.1)
				(type default)
			)
			(layer "F.Fab")
		)
		(fp_line
			(start -0.12065 0.2794)
			(end -0.12065 0.3048)
			(stroke
				(width 0.1)
				(type default)
			)
			(layer "F.Fab")
		)
		(fp_line
			(start -0.12065 0.3048)
			(end -0.67945 0.3048)
			(stroke
				(width 0.1)
				(type default)
			)
			(layer "F.Fab")
		)
		(fp_line
			(start 0.120396 0.2794)
			(end -0.12065 0.2794)
			(stroke
				(width 0.1)
				(type default)
			)
			(layer "F.Fab")
		)
		(fp_line
			(start 0.120396 0.3048)
			(end 0.120396 0.2794)
			(stroke
				(width 0.1)
				(type default)
			)
			(layer "F.Fab")
		)
		(fp_line
			(start 0.12065 -0.3048)
			(end 0.67945 -0.3048)
			(stroke
				(width 0.1)
				(type default)
			)
			(layer "F.Fab")
		)
		(fp_line
			(start 0.12065 -0.2794)
			(end 0.12065 -0.3048)
			(stroke
				(width 0.1)
				(type default)
			)
			(layer "F.Fab")
		)
		(fp_line
			(start 0.67945 -0.3048)
			(end 0.67945 0.3048)
			(stroke
				(width 0.1)
				(type default)
			)
			(layer "F.Fab")
		)
		(fp_line
			(start 0.67945 0.3048)
			(end 0.120396 0.3048)
			(stroke
				(width 0.1)
				(type default)
			)
			(layer "F.Fab")
		)
		(pad "1" smd circle
			(at -0.40005 0)
			(size 0 0)
			(layers "F.Cu" "F.Mask" "F.Paste")
			(net "PVDDCR_SOC_P1")
		)
		(pad "2" smd circle
			(at 0.40005 0)
			(size 0 0)
			(layers "F.Cu" "F.Mask" "F.Paste")
			(net "GND")
		)
	)
	(footprint ""
		(layer "F.Cu")
		(at 308.198266 -431.256186)
		(property "Reference" "R4136"
			(at 0 0 0)
			(layer "F.SilkS")
			(hide yes)
			(effects
				(font
					(size 1.27 1.27)
				)
			)
		)
		(property "Value" ""
			(at 0 0 0)
			(layer "F.Fab")
			(effects
				(font
					(size 1.27 1.27)
				)
			)
		)
		(duplicate_pad_numbers_are_jumpers no)
		(fp_line
			(start -0.7874 -0.4064)
			(end 0.7874 -0.4064)
			(stroke
				(width 0.1524)
				(type default)
			)
			(layer "F.SilkS")
		)
		(fp_line
			(start -0.7874 0.4064)
			(end -0.7874 -0.4064)
			(stroke
				(width 0.1524)
				(type default)
			)
			(layer "F.SilkS")
		)
		(fp_line
			(start 0.7874 -0.4064)
			(end 0.7874 0.4064)
			(stroke
				(width 0.1524)
				(type default)
			)
			(layer "F.SilkS")
		)
		(fp_line
			(start 0.7874 0.4064)
			(end -0.7874 0.4064)
			(stroke
				(width 0.1524)
				(type default)
			)
			(layer "F.SilkS")
		)
		(fp_line
			(start -0.67945 -0.305054)
			(end -0.12065 -0.305054)
			(stroke
				(width 0.1)
				(type default)
			)
			(layer "F.Fab")
		)
		(fp_line
			(start -0.67945 0.3048)
			(end -0.67945 -0.305054)
			(stroke
				(width 0.1)
				(type default)
			)
			(layer "F.Fab")
		)
		(fp_line
			(start -0.12065 -0.305054)
			(end -0.12065 -0.2794)
			(stroke
				(width 0.1)
				(type default)
			)
			(layer "F.Fab")
		)
		(fp_line
			(start -0.12065 -0.2794)
			(end 0.12065 -0.2794)
			(stroke
				(width 0.1)
				(type default)
			)
			(layer "F.Fab")
		)
		(fp_line
			(start -0.12065 0.2794)
			(end -0.12065 0.3048)
			(stroke
				(width 0.1)
				(type default)
			)
			(layer "F.Fab")
		)
		(fp_line
			(start -0.12065 0.3048)
			(end -0.67945 0.3048)
			(stroke
				(width 0.1)
				(type default)
			)
			(layer "F.Fab")
		)
		(fp_line
			(start 0.120396 0.2794)
			(end -0.12065 0.2794)
			(stroke
				(width 0.1)
				(type default)
			)
			(layer "F.Fab")
		)
		(fp_line
			(start 0.120396 0.3048)
			(end 0.120396 0.2794)
			(stroke
				(width 0.1)
				(type default)
			)
			(layer "F.Fab")
		)
		(fp_line
			(start 0.12065 -0.3048)
			(end 0.67945 -0.3048)
			(stroke
				(width 0.1)
				(type default)
			)
			(layer "F.Fab")
		)
		(fp_line
			(start 0.12065 -0.2794)
			(end 0.12065 -0.3048)
			(stroke
				(width 0.1)
				(type default)
			)
			(layer "F.Fab")
		)
		(fp_line
			(start 0.67945 -0.3048)
			(end 0.67945 0.3048)
			(stroke
				(width 0.1)
				(type default)
			)
			(layer "F.Fab")
		)
		(fp_line
			(start 0.67945 0.3048)
			(end 0.120396 0.3048)
			(stroke
				(width 0.1)
				(type default)
			)
			(layer "F.Fab")
		)
		(pad "1" smd circle
			(at -0.40005 0)
			(size 0 0)
			(layers "F.Cu" "F.Mask" "F.Paste")
			(net "PRSNT_CABLE_GPU_A2_N")
		)
		(pad "2" smd circle
			(at 0.40005 0)
			(size 0 0)
			(layers "F.Cu" "F.Mask" "F.Paste")
			(net "GND")
		)
	)
)
